(kicad_pcb
	(version 20241229)
	(generator "pcbnew")
	(generator_version "9.0")
	(general
		(thickness 1.61)
		(legacy_teardrops no)
	)
	(paper "A3")
	(title_block
		(title "SO-DIMM DDR5 Tester")
		(date "2025-11-26")
		(rev "1.3.0")
		(comment 9 "footprints 170-175 of 627")
	)
	(layers
		(0 "F.Cu" signal)
		(4 "In1.Cu" power)
		(6 "In2.Cu" mixed)
		(8 "In3.Cu" power)
		(10 "In4.Cu" mixed)
		(12 "In5.Cu" power)
		(14 "In6.Cu" mixed)
		(16 "In7.Cu" power)
		(18 "In8.Cu" power)
		(20 "In9.Cu" mixed)
		(22 "In10.Cu" power)
		(2 "B.Cu" signal)
		(9 "F.Adhes" user "F.Adhesive")
		(11 "B.Adhes" user "B.Adhesive")
		(13 "F.Paste" user)
		(15 "B.Paste" user)
		(5 "F.SilkS" user "F.Silkscreen")
		(7 "B.SilkS" user "B.Silkscreen")
		(1 "F.Mask" user)
		(3 "B.Mask" user)
		(17 "Dwgs.User" user "User.Drawings")
		(19 "Cmts.User" user "User.Comments")
		(21 "Eco1.User" user "User.Eco1")
		(23 "Eco2.User" user "User.Eco2")
		(25 "Edge.Cuts" user)
		(27 "Margin" user)
		(31 "F.CrtYd" user "F.Courtyard")
		(29 "B.CrtYd" user "B.Courtyard")
		(35 "F.Fab" user)
		(33 "B.Fab" user)
	)
	(footprint "antmicro-footprints:X2SON8_1.4x1x0.32mm_P0.35mm"
		(layer "F.Cu")
		(at 104.81 171.835)
		(property "Reference" "U33"
			(at -0.62 2.899 90)
			(layer "F.SilkS")
			(effects
				(font
					(size 0.7 0.7)
					(thickness 0.15)
				)
				(justify left bottom)
			)
		)
		(property "Value" "TXS0102DQER"
			(at 0 1.929 0)
			(layer "F.Fab")
			(effects
				(font
					(size 0.7 0.7)
					(thickness 0.15)
				)
				(justify left bottom)
			)
		)
		(property "Datasheet" "https://www.ti.com/lit/ds/symlink/txs0102.pdf?ts=1637914596981&ref_url=https%253A%252F%252Fwww.ti.com%252Fstore%252Fti%252Fen%252Fp%252Fproduct%252F%253Fp%253DTXS0102DCTR%2526keyMatch%253DTXS0102DCTR%2526tisearch%253Dsearch-everything%2526usecase%253DOPN"
			(at 0 0 0)
			(layer "F.Fab")
			(hide yes)
			(effects
				(font
					(size 1.27 1.27)
					(thickness 0.15)
				)
			)
		)
		(property "Author" "Antmicro"
			(at 0 0 0)
			(layer "F.Fab")
			(hide yes)
			(effects
				(font
					(size 1 1)
					(thickness 0.15)
				)
			)
		)
		(property "License" "Apache-2.0"
			(at 0 0 0)
			(layer "F.Fab")
			(hide yes)
			(effects
				(font
					(size 1 1)
					(thickness 0.15)
				)
			)
		)
		(property "MPN" "TXS0102DQER"
			(at 0 0 0)
			(layer "F.Fab")
			(hide yes)
			(effects
				(font
					(size 1 1)
					(thickness 0.15)
				)
			)
		)
		(property "Manufacturer" "Texas Instruments"
			(at 0 0 0)
			(layer "F.Fab")
			(hide yes)
			(effects
				(font
					(size 1 1)
					(thickness 0.15)
				)
			)
		)
		(sheetname "/Debug FTDI/")
		(sheetfile "debug-ftdi.kicad_sch")
		(attr smd)
		(fp_line
			(start -0.6 -0.801)
			(end -0.6 -0.7)
			(stroke
				(width 0.15)
				(type solid)
			)
			(layer "F.SilkS")
		)
		(fp_line
			(start -0.6 0.7)
			(end -0.6 0.801)
			(stroke
				(width 0.15)
				(type solid)
			)
			(layer "F.SilkS")
		)
		(fp_line
			(start -0.6 0.801)
			(end -0.5 0.801)
			(stroke
				(width 0.15)
				(type solid)
			)
			(layer "F.SilkS")
		)
		(fp_line
			(start -0.402 -0.801)
			(end -0.6 -0.801)
			(stroke
				(width 0.15)
				(type solid)
			)
			(layer "F.SilkS")
		)
		(fp_line
			(start 0.598 -0.801)
			(end 0.498 -0.801)
			(stroke
				(width 0.15)
				(type solid)
			)
			(layer "F.SilkS")
		)
		(fp_line
			(start 0.598 -0.7)
			(end 0.598 -0.801)
			(stroke
				(width 0.15)
				(type solid)
			)
			(layer "F.SilkS")
		)
		(fp_line
			(start 0.598 0.7)
			(end 0.598 0.801)
			(stroke
				(width 0.15)
				(type solid)
			)
			(layer "F.SilkS")
		)
		(fp_line
			(start 0.598 0.801)
			(end 0.498 0.801)
			(stroke
				(width 0.15)
				(type solid)
			)
			(layer "F.SilkS")
		)
		(fp_circle
			(center -0.81 -0.77)
			(end -0.81 -0.72)
			(stroke
				(width 0.15)
				(type solid)
			)
			(fill yes)
			(layer "F.SilkS")
		)
		(fp_rect
			(start 0.75 -0.925)
			(end -0.75 0.925)
			(stroke
				(width 0.05)
				(type solid)
			)
			(fill no)
			(layer "F.CrtYd")
		)
		(fp_line
			(start -0.5 -0.729)
			(end -0.5 0.719)
			(stroke
				(width 0.15)
				(type solid)
			)
			(layer "F.Fab")
		)
		(fp_line
			(start -0.5 -0.724)
			(end 0.498 -0.724)
			(stroke
				(width 0.15)
				(type solid)
			)
			(layer "F.Fab")
		)
		(fp_line
			(start -0.5 0.724)
			(end 0.498 0.724)
			(stroke
				(width 0.15)
				(type solid)
			)
			(layer "F.Fab")
		)
		(fp_line
			(start 0.498 -0.719)
			(end 0.498 0.719)
			(stroke
				(width 0.15)
				(type solid)
			)
			(layer "F.Fab")
		)
		(pad "1" smd rect
			(at -0.43 -0.526 270)
			(size 0.17 0.5)
			(layers "F.Cu" "F.Mask" "F.Paste")
			(net 6 "/Debug FTDI/FTDI_3V3")
			(pinfunction "VCCA")
			(pintype "power_in")
		)
		(pad "2" smd rect
			(at -0.43 -0.175 270)
			(size 0.17 0.5)
			(layers "F.Cu" "F.Mask" "F.Paste")
			(net 644 "/Debug FTDI/FTDI_UART1_RX")
			(pinfunction "A1")
			(pintype "bidirectional")
		)
		(pad "3" smd rect
			(at -0.43 0.175 270)
			(size 0.17 0.5)
			(layers "F.Cu" "F.Mask" "F.Paste")
			(net 642 "/Debug FTDI/FTDI_UART1_TX")
			(pinfunction "A2")
			(pintype "bidirectional")
		)
		(pad "4" smd rect
			(at -0.43 0.526 270)
			(size 0.17 0.5)
			(layers "F.Cu" "F.Mask" "F.Paste")
			(net 1 "GND")
			(pinfunction "GND")
			(pintype "power_in")
		)
		(pad "5" smd rect
			(at 0.43 0.526 270)
			(size 0.17 0.5)
			(layers "F.Cu" "F.Mask" "F.Paste")
			(net 6 "/Debug FTDI/FTDI_3V3")
			(pinfunction "OE")
			(pintype "tri_state")
		)
		(pad "6" smd rect
			(at 0.43 0.175 270)
			(size 0.17 0.5)
			(layers "F.Cu" "F.Mask" "F.Paste")
			(net 749 "Net-(U33-B2)")
			(pinfunction "B2")
			(pintype "bidirectional")
		)
		(pad "7" smd rect
			(at 0.43 -0.175 270)
			(size 0.17 0.5)
			(layers "F.Cu" "F.Mask" "F.Paste")
			(net 748 "Net-(U33-B1)")
			(pinfunction "B1")
			(pintype "bidirectional")
		)
		(pad "8" smd rect
			(at 0.43 -0.526 270)
			(size 0.17 0.5)
			(layers "F.Cu" "F.Mask" "F.Paste")
			(net 200 "+3V3")
			(pinfunction "VCCB")
			(pintype "power_in")
		)
	)
	(footprint "antmicro-footprints:TP_SMD_1mm"
		(layer "F.Cu")
		(at 98.100501 145.376 90)
		(property "Reference" "TP7"
			(at 0 -0.731898 90)
			(layer "F.SilkS")
			(effects
				(font
					(size 0.7 0.7)
					(thickness 0.15)
				)
				(justify left bottom)
			)
		)
		(property "Value" "TP_1mm_SMD"
			(at 0 1.4 90)
			(layer "F.Fab")
			(effects
				(font
					(size 0.7 0.7)
					(thickness 0.15)
				)
				(justify left bottom)
			)
		)
		(property "Author" "Antmicro"
			(at 243.476501 47.275499 0)
			(layer "F.Fab")
			(hide yes)
			(effects
				(font
					(size 1 1)
					(thickness 0.15)
				)
			)
		)
		(property "License" "Apache-2.0"
			(at 243.476501 47.275499 0)
			(layer "F.Fab")
			(hide yes)
			(effects
				(font
					(size 1 1)
					(thickness 0.15)
				)
			)
		)
		(property "MPN" ""
			(at 243.476501 47.275499 0)
			(layer "F.Fab")
			(hide yes)
			(effects
				(font
					(size 1 1)
					(thickness 0.15)
				)
			)
		)
		(property "Manufacturer" ""
			(at 243.476501 47.275499 0)
			(layer "F.Fab")
			(hide yes)
			(effects
				(font
					(size 1 1)
					(thickness 0.15)
				)
			)
		)
		(sheetname "/I^{2}C/")
		(sheetfile "i2c.kicad_sch")
		(attr exclude_from_pos_files)
		(pad "1" smd circle
			(at 0 0 90)
			(size 1 1)
			(layers "F.Cu" "F.Mask")
			(net 387 "Net-(U16-EN)")
			(pinfunction "1")
			(pintype "passive")
		)
	)
	(footprint "antmicro-footprints:R_0402_1005Metric"
		(layer "F.Cu")
		(at 202.895501 187.6605 -90)
		(descr "Resistor SMD 0402")
		(tags "resistor SMD 0402")
		(property "Reference" "R164"
			(at 3.8395 -0.354499 270)
			(layer "F.SilkS")
			(effects
				(font
					(size 0.7 0.7)
					(thickness 0.15)
				)
				(justify left bottom)
			)
		)
		(property "Value" "R_0R_0402"
			(at -1.011843 1.772047 270)
			(layer "F.Fab")
			(effects
				(font
					(size 0.7 0.7)
					(thickness 0.15)
				)
				(justify left bottom)
			)
		)
		(property "Datasheet" "https://industrial.panasonic.com/cdbs/www-data/pdf/RDA0000/AOA0000C301.pdf"
			(at 0 0 270)
			(layer "F.Fab")
			(hide yes)
			(effects
				(font
					(size 1.27 1.27)
					(thickness 0.15)
				)
			)
		)
		(property "Author" "Antmicro"
			(at 15.235001 390.556001 0)
			(layer "F.Fab")
			(hide yes)
			(effects
				(font
					(size 1 1)
					(thickness 0.15)
				)
			)
		)
		(property "Current" "1A"
			(at 15.235001 390.556001 0)
			(layer "F.Fab")
			(hide yes)
			(effects
				(font
					(size 1 1)
					(thickness 0.15)
				)
			)
		)
		(property "License" "Apache-2.0"
			(at 15.235001 390.556001 0)
			(layer "F.Fab")
			(hide yes)
			(effects
				(font
					(size 1 1)
					(thickness 0.15)
				)
			)
		)
		(property "MPN" "ERJ2GE0R00X"
			(at 15.235001 390.556001 0)
			(layer "F.Fab")
			(hide yes)
			(effects
				(font
					(size 1 1)
					(thickness 0.15)
				)
			)
		)
		(property "Manufacturer" "Panasonic"
			(at 15.235001 390.556001 0)
			(layer "F.Fab")
			(hide yes)
			(effects
				(font
					(size 1 1)
					(thickness 0.15)
				)
			)
		)
		(property "Tolerance" ""
			(at 15.235001 390.556001 0)
			(layer "F.Fab")
			(hide yes)
			(effects
				(font
					(size 1 1)
					(thickness 0.15)
				)
			)
		)
		(property "Val" "0R"
			(at 15.235001 390.556001 0)
			(layer "F.Fab")
			(hide yes)
			(effects
				(font
					(size 1 1)
					(thickness 0.15)
				)
			)
		)
		(sheetname "/Supply/")
		(sheetfile "supply.kicad_sch")
		(attr smd)
		(fp_rect
			(start -0.93 -0.47)
			(end 0.93 0.47)
			(stroke
				(width 0.05)
				(type solid)
			)
			(fill no)
			(layer "F.CrtYd")
		)
		(fp_rect
			(start -0.5 -0.25)
			(end 0.5 0.25)
			(stroke
				(width 0.15)
				(type solid)
			)
			(fill no)
			(layer "F.Fab")
		)
		(pad "1" smd roundrect
			(at -0.485 0 270)
			(size 0.59 0.64)
			(layers "F.Cu" "F.Mask" "F.Paste")
			(roundrect_rratio 0.25)
			(net 220 "/Supply/FB4")
			(pintype "passive")
		)
		(pad "2" smd roundrect
			(at 0.485 0 270)
			(size 0.59 0.64)
			(layers "F.Cu" "F.Mask" "F.Paste")
			(roundrect_rratio 0.25)
			(net 58 "/Supply/1V7_local")
			(pintype "passive")
		)
	)
	(footprint "antmicro-footprints:Vishay_PowerPAK_1212-8_Single"
		(layer "F.Cu")
		(at 118.67 202.47 -90)
		(descr "PowerPAK 1212-8 Single")
		(tags "Vishay PowerPAK 1212-8 Single")
		(property "Reference" "Q13"
			(at 0 -2 270)
			(layer "F.SilkS")
			(hide yes)
			(effects
				(font
					(size 0.7 0.7)
					(thickness 0.15)
				)
				(justify left bottom)
			)
		)
		(property "Value" "SI7613DN-T1-GE3"
			(at 0 2.7 270)
			(layer "F.Fab")
			(effects
				(font
					(size 0.7 0.7)
					(thickness 0.15)
				)
				(justify left bottom)
			)
		)
		(property "Datasheet" "https://www.vishay.com/docs/64809/si7613dn.pdf"
			(at 0 0 270)
			(layer "F.Fab")
			(hide yes)
			(effects
				(font
					(size 1.27 1.27)
					(thickness 0.15)
				)
			)
		)
		(property "Author" "Antmicro"
			(at -83.8 321.14 0)
			(layer "F.Fab")
			(hide yes)
			(effects
				(font
					(size 1 1)
					(thickness 0.15)
				)
			)
		)
		(property "License" "Apache-2.0"
			(at -83.8 321.14 0)
			(layer "F.Fab")
			(hide yes)
			(effects
				(font
					(size 1 1)
					(thickness 0.15)
				)
			)
		)
		(property "MPN" "SI7613DN-T1-GE3"
			(at -83.8 321.14 0)
			(layer "F.Fab")
			(hide yes)
			(effects
				(font
					(size 1 1)
					(thickness 0.15)
				)
			)
		)
		(property "Manufacturer" "Vishay"
			(at -83.8 321.14 0)
			(layer "F.Fab")
			(hide yes)
			(effects
				(font
					(size 1 1)
					(thickness 0.15)
				)
			)
		)
		(sheetname "/Supply/")
		(sheetfile "supply.kicad_sch")
		(attr smd)
		(fp_line
			(start -1.635 1.634)
			(end 1.634 1.634)
			(stroke
				(width 0.15)
				(type solid)
			)
			(layer "F.SilkS")
		)
		(fp_line
			(start -1.635 1.3)
			(end -1.635 1.634)
			(stroke
				(width 0.15)
				(type solid)
			)
			(layer "F.SilkS")
		)
		(fp_line
			(start 1.634 1.3)
			(end 1.634 1.634)
			(stroke
				(width 0.15)
				(type solid)
			)
			(layer "F.SilkS")
		)
		(fp_line
			(start -1.651 -1.651)
			(end -1.651 -1.317)
			(stroke
				(width 0.15)
				(type solid)
			)
			(layer "F.SilkS")
		)
		(fp_line
			(start -1.651 -1.651)
			(end 1.648 -1.651)
			(stroke
				(width 0.15)
				(type solid)
			)
			(layer "F.SilkS")
		)
		(fp_line
			(start 1.648 -1.651)
			(end 1.648 -1.317)
			(stroke
				(width 0.15)
				(type solid)
			)
			(layer "F.SilkS")
		)
		(fp_circle
			(center -1.9 -1.4)
			(end -1.85 -1.4)
			(stroke
				(width 0.15)
				(type solid)
			)
			(fill yes)
			(layer "F.SilkS")
		)
		(fp_rect
			(start -2 -1.8)
			(end 2 1.798)
			(stroke
				(width 0.05)
				(type solid)
			)
			(fill no)
			(layer "F.CrtYd")
		)
		(fp_line
			(start -1.6425 -1.4175)
			(end -1.4175 -1.6425)
			(stroke
				(width 0.15)
				(type solid)
			)
			(layer "F.Fab")
		)
		(fp_rect
			(start -1.651 -1.651)
			(end 1.648 1.648)
			(stroke
				(width 0.15)
				(type solid)
			)
			(fill no)
			(layer "F.Fab")
		)
		(pad "1" smd rect
			(at -1.436 -0.99 270)
			(size 0.99 0.405)
			(layers "F.Cu" "F.Mask" "F.Paste")
			(net 38 "VDC")
			(pinfunction "S")
			(pintype "passive")
		)
		(pad "2" smd rect
			(at -1.436 -0.332 270)
			(size 0.99 0.405)
			(layers "F.Cu" "F.Mask" "F.Paste")
			(net 38 "VDC")
			(pinfunction "S")
			(pintype "passive")
		)
		(pad "3" smd rect
			(at -1.436 0.33 270)
			(size 0.99 0.405)
			(layers "F.Cu" "F.Mask" "F.Paste")
			(net 38 "VDC")
			(pinfunction "S")
			(pintype "passive")
		)
		(pad "4" smd rect
			(at -1.436 0.988 270)
			(size 0.99 0.405)
			(layers "F.Cu" "F.Mask" "F.Paste")
			(net 366 "Net-(Q13-G)")
			(pinfunction "G")
			(pintype "passive")
		)
		(pad "5" smd custom
			(at 0.557 0 270)
			(size 1.725 2.235)
			(layers "F.Cu" "F.Mask" "F.Paste")
			(net 596 "/Supply/12V_PCIE_fused")
			(pinfunction "D")
			(pintype "passive")
			(zone_connect 2)
			(options
				(clearance outline)
				(anchor rect)
			)
			(primitives
				(gr_poly
					(pts
						(xy 0.8625 0.1275) (xy 0.8625 -0.1275) (xy 1.3725 -0.1275) (xy 1.3725 -0.5325) (xy 0.8625 -0.5325)
						(xy 0.8625 -0.7875) (xy 1.3725 -0.7875) (xy 1.3725 -1.195) (xy 0.6125 -1.195) (xy 0.6125 1.195)
						(xy 1.3725 1.195) (xy 1.3725 0.7875) (xy 0.8625 0.7875) (xy 0.8625 0.5325) (xy 1.3725 0.5325)
						(xy 1.3725 0.1275)
					)
					(width 0)
					(fill yes)
				)
			)
		)
	)
	(footprint "antmicro-footprints:R_0402_1005Metric"
		(layer "F.Cu")
		(at 99.850501 115.026 -90)
		(descr "Resistor SMD 0402")
		(tags "resistor SMD 0402")
		(property "Reference" "R61"
			(at -1.122484 -0.772697 270)
			(layer "F.SilkS")
			(hide yes)
			(effects
				(font
					(size 0.7 0.7)
					(thickness 0.15)
				)
				(justify left bottom)
			)
		)
		(property "Value" "R_330R_0402"
			(at -1.011843 1.772047 270)
			(layer "F.Fab")
			(effects
				(font
					(size 0.7 0.7)
					(thickness 0.15)
				)
				(justify left bottom)
			)
		)
		(property "Datasheet" "https://www.bourns.com/docs/product-datasheets/cr.pdf"
			(at 0 0 270)
			(layer "F.Fab")
			(hide yes)
			(effects
				(font
					(size 1.27 1.27)
					(thickness 0.15)
				)
			)
		)
		(property "Author" "Antmicro"
			(at -15.175499 214.876501 0)
			(layer "F.Fab")
			(hide yes)
			(effects
				(font
					(size 1 1)
					(thickness 0.15)
				)
			)
		)
		(property "License" "Apache-2.0"
			(at -15.175499 214.876501 0)
			(layer "F.Fab")
			(hide yes)
			(effects
				(font
					(size 1 1)
					(thickness 0.15)
				)
			)
		)
		(property "MPN" "CR0402-FX-3300GLF"
			(at -15.175499 214.876501 0)
			(layer "F.Fab")
			(hide yes)
			(effects
				(font
					(size 1 1)
					(thickness 0.15)
				)
			)
		)
		(property "Manufacturer" "Bourns"
			(at -15.175499 214.876501 0)
			(layer "F.Fab")
			(hide yes)
			(effects
				(font
					(size 1 1)
					(thickness 0.15)
				)
			)
		)
		(property "Tolerance" "1%"
			(at -15.175499 214.876501 0)
			(layer "F.Fab")
			(hide yes)
			(effects
				(font
					(size 1 1)
					(thickness 0.15)
				)
			)
		)
		(property "Val" "330R"
			(at -15.175499 214.876501 0)
			(layer "F.Fab")
			(hide yes)
			(effects
				(font
					(size 1 1)
					(thickness 0.15)
				)
			)
		)
		(sheetname "/DDR5 SODIMM/")
		(sheetfile "ddr5-sodimm.kicad_sch")
		(attr smd)
		(fp_rect
			(start -0.93 -0.47)
			(end 0.93 0.47)
			(stroke
				(width 0.05)
				(type solid)
			)
			(fill no)
			(layer "F.CrtYd")
		)
		(fp_rect
			(start -0.5 -0.25)
			(end 0.5 0.25)
			(stroke
				(width 0.15)
				(type solid)
			)
			(fill no)
			(layer "F.Fab")
		)
		(pad "1" smd roundrect
			(at -0.485 0 270)
			(size 0.59 0.64)
			(layers "F.Cu" "F.Mask" "F.Paste")
			(roundrect_rratio 0.25)
			(net 312 "Net-(D9-C_{Y})")
			(pintype "passive")
		)
		(pad "2" smd roundrect
			(at 0.485 0 270)
			(size 0.59 0.64)
			(layers "F.Cu" "F.Mask" "F.Paste")
			(roundrect_rratio 0.25)
			(net 358 "Net-(Q9-D)")
			(pintype "passive")
		)
	)
	(footprint "antmicro-footprints:NetTie-2_SMD_Pad0.127mm"
		(layer "F.Cu")
		(at 200.274 173.974998)
		(descr "Net tie, 2 pin, 0.127mm  SMD pads")
		(tags "net tie")
		(property "Reference" "NT8"
			(at -0.128 -1.345 0)
			(layer "F.SilkS")
			(hide yes)
			(effects
				(font
					(size 0.7 0.7)
					(thickness 0.15)
				)
				(justify left bottom)
			)
		)
		(property "Value" "Net-Tie_P0.127mm"
			(at 0 1.199 0)
			(layer "F.Fab")
			(effects
				(font
					(size 0.7 0.7)
					(thickness 0.15)
				)
				(justify left bottom)
			)
		)
		(property "Author" "Antmicro"
			(at 0 0 0)
			(layer "F.Fab")
			(hide yes)
			(effects
				(font
					(size 1 1)
					(thickness 0.15)
				)
			)
		)
		(property "License" "Apache-2.0"
			(at 0 0 0)
			(layer "F.Fab")
			(hide yes)
			(effects
				(font
					(size 1 1)
					(thickness 0.15)
				)
			)
		)
		(property "MPN" ""
			(at 0 0 0)
			(layer "F.Fab")
			(hide yes)
			(effects
				(font
					(size 1 1)
					(thickness 0.15)
				)
			)
		)
		(property "Manufacturer" ""
			(at 0 0 0)
			(layer "F.Fab")
			(hide yes)
			(effects
				(font
					(size 1 1)
					(thickness 0.15)
				)
			)
		)
		(property ki_fp_filters "Net*Tie*")
		(sheetname "/Supply/")
		(sheetfile "supply.kicad_sch")
		(attr smd exclude_from_pos_files exclude_from_bom)
		(net_tie_pad_groups "1, 2")
		(fp_poly
			(pts
				(xy -0.0635 -0.0635) (xy 0.0625 -0.0635) (xy 0.0625 0.0635) (xy -0.0635 0.0635)
			)
			(stroke
				(width 0)
				(type solid)
			)
			(fill yes)
			(layer "F.Cu")
		)
		(pad "1" smd roundrect
			(at -0.127 0 180)
			(size 0.127 0.127)
			(layers "F.Cu")
			(roundrect_rratio 0.5)
			(chamfer_ratio 0)
			(chamfer top_left bottom_left)
			(net 90 "/Supply/1V2_SEN_+")
			(pinfunction "1")
			(pintype "passive")
		)
		(pad "2" smd roundrect
			(at 0.126 0)
			(size 0.127 0.127)
			(layers "F.Cu")
			(roundrect_rratio 0.5)
			(chamfer_ratio 0)
			(chamfer top_left bottom_left)
			(net 56 "/Supply/1V2_local")
			(pinfunction "2")
			(pintype "passive")
		)
	)
)
